# BASEBOARD_FAB2 (Tioga Pass) — schematic netlist excerpt (pin names and nets, part order shuffled) for the footprints in the layout excerpt that follows; sources: Cadence DE-HDL packaged netlist, KiCad conversion of Wiwynn_Tioga_Pass_MB.brd

R25W139  RES  33.2 1% CHIP  pkg 0402  page 252 : A = VGA_REAR_VSYNC_S ; B = V_IO_VSYNC_J
C7B21  CAP_A  22.0UF 4V 20% X6S  pkg 0603V  page 131 : A = P1V05_PCH_STBY ; B = GND
R2U1  RES  20.0 1% CHIP  pkg 0402  page 159 : A = SMB_BMC_PMBUS_STBY_LVC3_SCL_R ; B = SMB_BMC_PMBUS_STBY_LVC3_SCL

(kicad_pcb
	(version 20260206)
	(generator "pcbnew")
	(generator_version "10.0")
	(general
		(thickness 1.6)
		(legacy_teardrops no)
	)
	(paper "A4")
	(title_block
		(title "Wiwynn_Tioga_Pass_MB.brd")
		(comment 1 "Tioga Pass / footprints 2061-2063 of 4770")
	)
	(layers
		(0 "F.Cu" signal "TOP")
		(4 "In1.Cu" signal "L2GND")
		(6 "In2.Cu" signal "L3")
		(8 "In3.Cu" signal "L4GND")
		(10 "In4.Cu" signal "L5")
		(12 "In5.Cu" signal "L6GND")
		(14 "In6.Cu" signal "L7VCC")
		(16 "In7.Cu" signal "L8VCC")
		(18 "In8.Cu" signal "L9GND")
		(20 "In9.Cu" signal "L10")
		(22 "In10.Cu" signal "L11GND")
		(24 "In11.Cu" signal "L12")
		(26 "In12.Cu" signal "L13GND")
		(2 "B.Cu" signal "BOTTOM")
		(9 "F.Adhes" user "F.Adhesive")
		(11 "B.Adhes" user "B.Adhesive")
		(13 "F.Paste" user "Package Geometry/Pastemask Top")
		(15 "B.Paste" user "Package Geometry/Pastemask Bottom")
		(5 "F.SilkS" user "Ref Des/Silkscreen Top")
		(7 "B.SilkS" user "Ref Des/Silkscreen Bottom")
		(1 "F.Mask" user "Board Geometry/Soldermask Top")
		(3 "B.Mask" user "Board Geometry/Soldermask Bottom")
		(17 "Dwgs.User" user "User.Drawings")
		(19 "Cmts.User" user "User.Comments")
		(21 "Eco1.User" user "User.Eco1")
		(23 "Eco2.User" user "User.Eco2")
		(25 "Edge.Cuts" user "Board Geometry/Outline")
		(27 "Margin" user)
		(31 "F.CrtYd" user "Package Geometry/Place Bound Top")
		(29 "B.CrtYd" user "Package Geometry/Place Bound Bottom")
		(35 "F.Fab" user "Ref Des/Assembly Top")
		(33 "B.Fab" user "Ref Des/Assembly Bottom")
	)
	(footprint ""
		(layer "F.Cu")
		(at 492.228886 -47.458884)
		(property "Reference" "R25W139"
			(at -0.8382 -0.67818 0)
			(unlocked yes)
			(layer "F.SilkS")
			(effects
				(font
					(size 0.4064 0.254)
					(thickness 0.1524)
				)
				(justify left)
			)
		)
		(property "Value" ""
			(at 0 0 0)
			(layer "F.Fab")
			(effects
				(font
					(size 1.27 1.27)
				)
			)
		)
		(duplicate_pad_numbers_are_jumpers no)
		(fp_poly
			(pts
				(xy -0.2794 -0.1016) (xy 0.2794 -0.1016) (xy 0.2794 0.9906) (xy -0.2794 0.9906)
			)
			(stroke
				(width 0)
				(type default)
			)
			(fill no)
			(layer "F.CrtYd")
		)
		(fp_line
			(start -0.2794 -0.1016)
			(end -0.2794 0.9906)
			(stroke
				(width 0.1)
				(type default)
			)
			(layer "F.Fab")
		)
		(fp_line
			(start -0.2794 0.9906)
			(end 0.2794 0.9906)
			(stroke
				(width 0.1)
				(type default)
			)
			(layer "F.Fab")
		)
		(fp_line
			(start 0.2794 -0.1016)
			(end -0.2794 -0.1016)
			(stroke
				(width 0.1)
				(type default)
			)
			(layer "F.Fab")
		)
		(fp_line
			(start 0.2794 0.9906)
			(end 0.2794 -0.1016)
			(stroke
				(width 0.1)
				(type default)
			)
			(layer "F.Fab")
		)
		(pad "1" smd rect
			(at 0 0)
			(size 0.508 0.508)
			(layers "F.Cu" "F.Mask" "F.Paste")
			(net "VGA_REAR_VSYNC_S")
		)
		(pad "2" smd rect
			(at 0 0.889)
			(size 0.508 0.508)
			(layers "F.Cu" "F.Mask" "F.Paste")
			(net "V_IO_VSYNC_J")
		)
		(zone
			(layer "F.Cu")
			(hatch none 0.5)
			(connect_pads
				(clearance 0)
			)
			(min_thickness 0.25)
			(keepout
				(tracks allowed)
				(vias not_allowed)
				(pads allowed)
				(copperpour not_allowed)
				(footprints allowed)
			)
			(placement
				(enabled no)
				(sheetname "")
			)
			(fill
				(thermal_gap 0.5)
				(thermal_bridge_width 0.5)
				(island_removal_mode 0)
			)
			(polygon
				(pts
					(xy 491.974886 -47.204884) (xy 492.482886 -47.204884) (xy 492.482886 -46.823884) (xy 491.974886 -46.823884)
				)
			)
		)
		(zone
			(layer "F.Cu")
			(hatch none 0.5)
			(connect_pads
				(clearance 0)
			)
			(min_thickness 0.25)
			(keepout
				(tracks not_allowed)
				(vias allowed)
				(pads allowed)
				(copperpour not_allowed)
				(footprints allowed)
			)
			(placement
				(enabled no)
				(sheetname "")
			)
			(fill
				(thermal_gap 0.5)
				(thermal_bridge_width 0.5)
				(island_removal_mode 0)
			)
			(polygon
				(pts
					(xy 491.974886 -46.823884) (xy 492.482886 -46.823884) (xy 492.482886 -47.204884) (xy 491.974886 -47.204884)
				)
			)
		)
	)
	(footprint ""
		(layer "F.Cu")
		(at 368.4016 -130.429 180)
		(property "Reference" "C7B21"
			(at 0 0 180)
			(layer "F.SilkS")
			(hide yes)
			(effects
				(font
					(size 1.27 1.27)
				)
			)
		)
		(property "Value" ""
			(at 0 0 180)
			(layer "F.Fab")
			(effects
				(font
					(size 1.27 1.27)
				)
			)
		)
		(duplicate_pad_numbers_are_jumpers no)
		(fp_poly
			(pts
				(xy -0.4953 -0.2032) (xy 0.4953 -0.2032) (xy 0.4953 1.6002) (xy -0.4953 1.6002)
			)
			(stroke
				(width 0)
				(type default)
			)
			(fill no)
			(layer "F.CrtYd")
		)
		(fp_line
			(start 0.4953 1.6002)
			(end -0.4953 1.6002)
			(stroke
				(width 0.1)
				(type default)
			)
			(layer "F.Fab")
		)
		(fp_line
			(start 0.4953 -0.2032)
			(end 0.4953 1.6002)
			(stroke
				(width 0.1)
				(type default)
			)
			(layer "F.Fab")
		)
		(fp_line
			(start -0.4953 1.6002)
			(end -0.4953 -0.2032)
			(stroke
				(width 0.1)
				(type default)
			)
			(layer "F.Fab")
		)
		(fp_line
			(start -0.4953 -0.2032)
			(end 0.4953 -0.2032)
			(stroke
				(width 0.1)
				(type default)
			)
			(layer "F.Fab")
		)
		(pad "1" smd rect
			(at 0 0 180)
			(size 0.762 0.889)
			(layers "F.Cu" "F.Mask" "F.Paste")
			(net "P1V05_PCH_STBY")
		)
		(pad "2" smd rect
			(at 0 1.397 180)
			(size 0.762 0.889)
			(layers "F.Cu" "F.Mask" "F.Paste")
			(net "GND")
		)
		(zone
			(layer "F.Cu")
			(hatch none 0.5)
			(connect_pads
				(clearance 0)
			)
			(min_thickness 0.25)
			(keepout
				(tracks not_allowed)
				(vias allowed)
				(pads allowed)
				(copperpour not_allowed)
				(footprints allowed)
			)
			(placement
				(enabled no)
				(sheetname "")
			)
			(fill
				(thermal_gap 0.5)
				(thermal_bridge_width 0.5)
				(island_removal_mode 0)
			)
			(polygon
				(pts
					(xy 368.7826 -130.8735) (xy 368.0206 -130.8735) (xy 368.0206 -131.3815) (xy 368.7826 -131.3815)
				)
			)
		)
	)
	(footprint ""
		(layer "F.Cu")
		(at 419.0746 -21.6535)
		(property "Reference" "R2U1"
			(at 0 0 0)
			(layer "F.SilkS")
			(hide yes)
			(effects
				(font
					(size 1.27 1.27)
				)
			)
		)
		(property "Value" ""
			(at 0 0 0)
			(layer "F.Fab")
			(effects
				(font
					(size 1.27 1.27)
				)
			)
		)
		(duplicate_pad_numbers_are_jumpers no)
		(fp_poly
			(pts
				(xy -0.2794 -0.1016) (xy 0.2794 -0.1016) (xy 0.2794 0.9906) (xy -0.2794 0.9906)
			)
			(stroke
				(width 0)
				(type default)
			)
			(fill no)
			(layer "F.CrtYd")
		)
		(fp_line
			(start -0.2794 -0.1016)
			(end -0.2794 0.9906)
			(stroke
				(width 0.1)
				(type default)
			)
			(layer "F.Fab")
		)
		(fp_line
			(start -0.2794 0.9906)
			(end 0.2794 0.9906)
			(stroke
				(width 0.1)
				(type default)
			)
			(layer "F.Fab")
		)
		(fp_line
			(start 0.2794 -0.1016)
			(end -0.2794 -0.1016)
			(stroke
				(width 0.1)
				(type default)
			)
			(layer "F.Fab")
		)
		(fp_line
			(start 0.2794 0.9906)
			(end 0.2794 -0.1016)
			(stroke
				(width 0.1)
				(type default)
			)
			(layer "F.Fab")
		)
		(pad "1" smd rect
			(at 0 0)
			(size 0.508 0.508)
			(layers "F.Cu" "F.Mask" "F.Paste")
			(net "SMB_BMC_PMBUS_STBY_LVC3_SCL_R")
		)
		(pad "2" smd rect
			(at 0 0.889)
			(size 0.508 0.508)
			(layers "F.Cu" "F.Mask" "F.Paste")
			(net "SMB_BMC_PMBUS_STBY_LVC3_SCL")
		)
		(zone
			(layer "F.Cu")
			(hatch none 0.5)
			(connect_pads
				(clearance 0)
			)
			(min_thickness 0.25)
			(keepout
				(tracks allowed)
				(vias not_allowed)
				(pads allowed)
				(copperpour not_allowed)
				(footprints allowed)
			)
			(placement
				(enabled no)
				(sheetname "")
			)
			(fill
				(thermal_gap 0.5)
				(thermal_bridge_width 0.5)
				(island_removal_mode 0)
			)
			(polygon
				(pts
					(xy 418.8206 -21.3995) (xy 419.3286 -21.3995) (xy 419.3286 -21.0185) (xy 418.8206 -21.0185)
				)
			)
		)
		(zone
			(layer "F.Cu")
			(hatch none 0.5)
			(connect_pads
				(clearance 0)
			)
			(min_thickness 0.25)
			(keepout
				(tracks not_allowed)
				(vias allowed)
				(pads allowed)
				(copperpour not_allowed)
				(footprints allowed)
			)
			(placement
				(enabled no)
				(sheetname "")
			)
			(fill
				(thermal_gap 0.5)
				(thermal_bridge_width 0.5)
				(island_removal_mode 0)
			)
			(polygon
				(pts
					(xy 418.8206 -21.0185) (xy 419.3286 -21.0185) (xy 419.3286 -21.3995) (xy 418.8206 -21.3995)
				)
			)
		)
	)
)
